# S9S_MB_2U (Grand Teton) — schematic netlist excerpt (pin names and nets, part order shuffled) for the footprints in the layout excerpt that follows; sources: Cadence DE-HDL packaged netlist, KiCad conversion of 03242023_DA0F0TMBIJ0_F0T_Motherboard_J_brd_V01_OCP.brd

PU71_P0_3  ISL99390FRZTR5935  ISL99390FRZ-TR5935 IC  pkg QFN21_6X5XB  page 272
  VOS  = PVCCFA_EHV_FIVRA_CPU0_VOS3
  AGND  = GND
  VCC  = PVCCFA_EHV_FIVRA_CPU0_VDD3
  PVCC  = PVCCFA_EHV_FIVRA_CPU0_PVCC1
  PGND1  = GND
  GL1  = NC
  PGND2  = GND
  SW  = SW_PVCCFA_EHV_FIVRA_CPU0_SW3
  VIN1  = SW_P12V_PVCCFA_EHV_FIVRA_CPU0_R
  VIN2  = SW_P12V_PVCCFA_EHV_FIVRA_CPU0_R
  DNC  = NC
  PHASE  = SW_PVCCFA_EHV_FIVRA_CPU0_BOOTR3
  BOOT  = SW_PVCCFA_EHV_FIVRA_CPU0_BOOT3
  PWM  = PVCCFA_EHV_FIVRA_CPU0_PWM3
  EN  = PVCCFA_EHV_FIVRA_CPU0_VDD3
  TOUT_FLT  = PVCCFA_EHV_FIVRA_CPU0_BTSEN
  LSET  = PVCCFA_EHV_FIVRA_CPU0_LSET3
  IOUT  = PVCCFA_EHV_FIVRA_CPU0_IMON3
  REFIN  = PVCCIN_CPU0_VREF
  PGND3  = GND
  GL2  = NC

(kicad_pcb
	(version 20260206)
	(generator "pcbnew")
	(generator_version "10.0")
	(general
		(thickness 1.6)
		(legacy_teardrops no)
	)
	(paper "A4")
	(title_block
		(title "03242023_DA0F0TMBIJ0_F0T_Motherboard_J_brd_V01_OCP.brd")
		(comment 1 "Grand Teton / footprints 1698-1698 of 6105")
	)
	(layers
		(0 "F.Cu" signal "TOP")
		(4 "In1.Cu" signal "GND")
		(6 "In2.Cu" signal "IN1")
		(8 "In3.Cu" signal "GND1")
		(10 "In4.Cu" signal "IN2")
		(12 "In5.Cu" signal "GND2")
		(14 "In6.Cu" signal "IN3")
		(16 "In7.Cu" signal "GND3")
		(18 "In8.Cu" signal "VCC")
		(20 "In9.Cu" signal "VCC1")
		(22 "In10.Cu" signal "GND4")
		(24 "In11.Cu" signal "IN4")
		(26 "In12.Cu" signal "GND5")
		(28 "In13.Cu" signal "IN5")
		(30 "In14.Cu" signal "GND6")
		(32 "In15.Cu" signal "IN6")
		(34 "In16.Cu" signal "GND7")
		(2 "B.Cu" signal "BOTTOM")
		(9 "F.Adhes" user "F.Adhesive")
		(11 "B.Adhes" user "B.Adhesive")
		(13 "F.Paste" user "Package Geometry/Pastemask Top")
		(15 "B.Paste" user "Package Geometry/Pastemask Bottom")
		(5 "F.SilkS" user "Ref Des/Silkscreen Top")
		(7 "B.SilkS" user "Ref Des/Silkscreen Bottom")
		(1 "F.Mask" user "Board Geometry/Soldermask Top")
		(3 "B.Mask" user "Board Geometry/Soldermask Bottom")
		(17 "Dwgs.User" user "User.Drawings")
		(19 "Cmts.User" user "User.Comments")
		(21 "Eco1.User" user "User.Eco1")
		(23 "Eco2.User" user "User.Eco2")
		(25 "Edge.Cuts" user "Board Geometry/Outline")
		(27 "Margin" user)
		(31 "F.CrtYd" user "Package Geometry/Place Bound Top")
		(29 "B.CrtYd" user "Package Geometry/Place Bound Bottom")
		(35 "F.Fab" user "Ref Des/Assembly Top")
		(33 "B.Fab" user "Ref Des/Assembly Bottom")
	)
	(footprint ""
		(layer "F.Cu")
		(at 425.84878 -362.087668)
		(property "Reference" "PU71_P0_3"
			(at 8.44042 -2.23647 0)
			(unlocked yes)
			(layer "F.SilkS")
			(effects
				(font
					(size 0.7874 0.5842)
					(thickness 0.1524)
				)
				(justify left)
			)
		)
		(property "Value" ""
			(at 0 0 0)
			(layer "F.Fab")
			(effects
				(font
					(size 1.27 1.27)
				)
			)
		)
		(duplicate_pad_numbers_are_jumpers no)
		(fp_line
			(start -2.500122 -2.999994)
			(end -2.24409 -2.999994)
			(stroke
				(width 0.1524)
				(type default)
			)
			(layer "F.SilkS")
		)
		(fp_line
			(start -2.500122 -2.529078)
			(end -2.500122 -2.999994)
			(stroke
				(width 0.1524)
				(type default)
			)
			(layer "F.SilkS")
		)
		(fp_line
			(start -2.500122 0.6604)
			(end -2.500122 0.229108)
			(stroke
				(width 0.1524)
				(type default)
			)
			(layer "F.SilkS")
		)
		(fp_line
			(start -2.500122 2.999994)
			(end -2.500122 2.339594)
			(stroke
				(width 0.1524)
				(type default)
			)
			(layer "F.SilkS")
		)
		(fp_line
			(start -2.2987 2.999994)
			(end -2.500122 2.999994)
			(stroke
				(width 0.1524)
				(type default)
			)
			(layer "F.SilkS")
		)
		(fp_line
			(start 2.31394 -2.999994)
			(end 2.500122 -2.999994)
			(stroke
				(width 0.1524)
				(type default)
			)
			(layer "F.SilkS")
		)
		(fp_line
			(start 2.500122 -2.999994)
			(end 2.500122 -2.44348)
			(stroke
				(width 0.1524)
				(type default)
			)
			(layer "F.SilkS")
		)
		(fp_line
			(start 2.500122 2.339594)
			(end 2.500122 2.999994)
			(stroke
				(width 0.1524)
				(type default)
			)
			(layer "F.SilkS")
		)
		(fp_line
			(start 2.500122 2.999994)
			(end 2.2987 2.999994)
			(stroke
				(width 0.1524)
				(type default)
			)
			(layer "F.SilkS")
		)
		(fp_poly
			(pts
				(xy -2.218182 -3.583432) (xy -2.726182 -2.567432) (xy -3.234182 -3.583432)
			)
			(stroke
				(width 0)
				(type default)
			)
			(fill yes)
			(layer "F.SilkS")
		)
		(fp_line
			(start -2.500122 -2.999994)
			(end 2.500122 -2.999994)
			(stroke
				(width 0.1)
				(type default)
			)
			(layer "F.Fab")
		)
		(fp_line
			(start -2.500122 2.999994)
			(end -2.500122 -2.999994)
			(stroke
				(width 0.1)
				(type default)
			)
			(layer "F.Fab")
		)
		(fp_line
			(start 2.500122 -2.999994)
			(end 2.500122 2.999994)
			(stroke
				(width 0.1)
				(type default)
			)
			(layer "F.Fab")
		)
		(fp_line
			(start 2.500122 2.999994)
			(end -2.500122 2.999994)
			(stroke
				(width 0.1)
				(type default)
			)
			(layer "F.Fab")
		)
		(fp_poly
			(pts
				(xy -4.218432 -2.783078) (xy -4.218432 -1.767078) (xy -3.202432 -2.275078)
			)
			(stroke
				(width 0)
				(type default)
			)
			(fill yes)
			(layer "F.Fab")
		)
		(pad "1" smd rect
			(at -2.400046 -2.275078 90)
			(size 0.2286 0.6096)
			(layers "F.Cu" "F.Mask" "F.Paste")
			(net "PVCCFA_EHV_FIVRA_CPU0_VOS3")
		)
		(pad "2" smd rect
			(at -2.400046 -1.82499 90)
			(size 0.2286 0.6096)
			(layers "F.Cu" "F.Mask" "F.Paste")
			(net "GND")
		)
		(pad "3" smd rect
			(at -2.400046 -1.374902 90)
			(size 0.2286 0.6096)
			(layers "F.Cu" "F.Mask" "F.Paste")
			(net "PVCCFA_EHV_FIVRA_CPU0_VDD3")
		)
		(pad "4" smd rect
			(at -2.400046 -0.925068 90)
			(size 0.2286 0.6096)
			(layers "F.Cu" "F.Mask" "F.Paste")
			(net "PVCCFA_EHV_FIVRA_CPU0_PVCC1")
		)
		(pad "5" smd rect
			(at -2.400046 -0.47498 90)
			(size 0.2286 0.6096)
			(layers "F.Cu" "F.Mask" "F.Paste")
			(net "GND")
		)
		(pad "6" smd rect
			(at -2.400046 -0.024892 90)
			(size 0.2286 0.6096)
			(layers "F.Cu" "F.Mask" "F.Paste")
			(net "Net_8511")
		)
		(pad "7_9-20_24" smd circle
			(at 0 1.150112 90)
			(size 0 0)
			(layers "F.Cu" "F.Mask" "F.Paste")
			(net "GND")
		)
		(pad "10_19" smd rect
			(at 0 2.899918 90)
			(size 0.6096 4.318)
			(layers "F.Cu" "F.Mask" "F.Paste")
			(net "SW_PVCCFA_EHV_FIVRA_CPU0_SW3")
		)
		(pad "25_29" smd rect
			(at 1.549908 -1.279906 270)
			(size 2.0574 2.3114)
			(layers "F.Cu" "F.Mask" "F.Paste")
			(net "SW_P12V_PVCCFA_EHV_FIVRA_CPU0_R")
		)
		(pad "30" smd rect
			(at 2.05994 -2.899918)
			(size 0.2286 0.6096)
			(layers "F.Cu" "F.Mask" "F.Paste")
			(net "SW_P12V_PVCCFA_EHV_FIVRA_CPU0_R")
		)
		(pad "31" smd rect
			(at 1.610106 -2.899918)
			(size 0.2286 0.6096)
			(layers "F.Cu" "F.Mask" "F.Paste")
			(net "Net_8512")
		)
		(pad "32" smd rect
			(at 1.160018 -2.899918)
			(size 0.2286 0.6096)
			(layers "F.Cu" "F.Mask" "F.Paste")
			(net "SW_PVCCFA_EHV_FIVRA_CPU0_BOOTR3")
		)
		(pad "33" smd rect
			(at 0.70993 -2.899918)
			(size 0.2286 0.6096)
			(layers "F.Cu" "F.Mask" "F.Paste")
			(net "SW_PVCCFA_EHV_FIVRA_CPU0_BOOT3")
		)
		(pad "34" smd rect
			(at 0.260096 -2.899918)
			(size 0.2286 0.6096)
			(layers "F.Cu" "F.Mask" "F.Paste")
			(net "PVCCFA_EHV_FIVRA_CPU0_PWM3")
		)
		(pad "35" smd rect
			(at -0.189992 -2.899918)
			(size 0.2286 0.6096)
			(layers "F.Cu" "F.Mask" "F.Paste")
			(net "PVCCFA_EHV_FIVRA_CPU0_VDD3")
		)
		(pad "36" smd rect
			(at -0.64008 -2.899918)
			(size 0.2286 0.6096)
			(layers "F.Cu" "F.Mask" "F.Paste")
			(net "PVCCFA_EHV_FIVRA_CPU0_BTSEN")
		)
		(pad "37" smd rect
			(at -1.089914 -2.899918)
			(size 0.2286 0.6096)
			(layers "F.Cu" "F.Mask" "F.Paste")
			(net "PVCCFA_EHV_FIVRA_CPU0_LSET3")
		)
		(pad "38" smd rect
			(at -1.540002 -2.899918)
			(size 0.2286 0.6096)
			(layers "F.Cu" "F.Mask" "F.Paste")
			(net "PVCCFA_EHV_FIVRA_CPU0_IMON3")
		)
		(pad "39" smd rect
			(at -1.99009 -2.899918)
			(size 0.2286 0.6096)
			(layers "F.Cu" "F.Mask" "F.Paste")
			(net "PVCCIN_CPU0_VREF")
		)
		(pad "40" smd rect
			(at -0.87503 -1.27508)
			(size 1.7526 1.9558)
			(layers "F.Cu" "F.Mask" "F.Paste")
			(net "GND")
		)
		(pad "41" smd rect
			(at -1.525016 0.249936 270)
			(size 0.3048 0.4572)
			(layers "F.Cu" "F.Mask" "F.Paste")
			(net "Net_8510")
		)
		(zone
			(layer "F.Cu")
			(hatch none 0.5)
			(connect_pads
				(clearance 0)
			)
			(min_thickness 0.25)
			(keepout
				(tracks not_allowed)
				(vias allowed)
				(pads allowed)
				(copperpour not_allowed)
				(footprints allowed)
			)
			(placement
				(enabled no)
				(sheetname "")
			)
			(fill
				(thermal_gap 0.5)
				(thermal_bridge_width 0.5)
				(island_removal_mode 0)
			)
			(polygon
				(pts
					(xy 423.348658 -359.087674) (xy 423.348658 -359.836974) (xy 428.348902 -359.836974) (xy 428.348902 -359.087674)
					(xy 428.05858 -359.087674) (xy 428.05858 -359.54335) (xy 423.63898 -359.54335) (xy 423.63898 -359.087674)
				)
			)
		)
		(zone
			(layer "F.Cu")
			(hatch none 0.5)
			(connect_pads
				(clearance 0)
			)
			(min_thickness 0.25)
			(keepout
				(tracks not_allowed)
				(vias allowed)
				(pads allowed)
				(copperpour not_allowed)
				(footprints allowed)
			)
			(placement
				(enabled no)
				(sheetname "")
			)
			(fill
				(thermal_gap 0.5)
				(thermal_bridge_width 0.5)
				(island_removal_mode 0)
			)
			(polygon
				(pts
					(xy 424.07332 -362.334048) (xy 424.82262 -362.334048) (xy 424.82262 -362.016548) (xy 424.898058 -362.016548)
					(xy 424.898058 -361.385866) (xy 424.85056 -361.338368) (xy 423.348658 -361.338368) (xy 423.348658 -361.79506)
					(xy 424.044364 -361.79506) (xy 424.044364 -361.634532) (xy 424.603164 -361.634532) (xy 424.603164 -362.040932)
					(xy 424.044364 -362.040932) (xy 424.044364 -361.82046) (xy 423.348658 -361.82046) (xy 423.348658 -361.94746)
					(xy 423.804334 -361.94746) (xy 423.804334 -362.311188) (xy 424.07332 -362.311188)
				)
			)
		)
	)
)
